# BASEBOARD_FAB2 (Tioga Pass) — schematic netlist excerpt (pin names and nets, part order shuffled) for the footprints in the layout excerpt that follows; sources: Cadence DE-HDL packaged netlist, KiCad conversion of Wiwynn_Tioga_Pass_MB.brd

C2T20  CAP  0.22UF 16V 10% X7R  pkg 0402  page 185 : A = P3E_PCH_M2_TX_C_DP<3> ; B = P3E_PCH_M2_TX_DP<3>
R9P29  RES  100.0K 1% CHIP  pkg 0402  page 199 : A = P12V_PSU ; B = A_HSC_UV
R25W74  RES  0.0 5% CHIP  pkg 0402  page 146 : A = RST_PLTRST_BUF_N ; B = RST_BMC_LVC3_N

(kicad_pcb
	(version 20260206)
	(generator "pcbnew")
	(generator_version "10.0")
	(general
		(thickness 1.6)
		(legacy_teardrops no)
	)
	(paper "A4")
	(title_block
		(title "Wiwynn_Tioga_Pass_MB.brd")
		(comment 1 "Tioga Pass / footprints 2373-2375 of 4770")
	)
	(layers
		(0 "F.Cu" signal "TOP")
		(4 "In1.Cu" signal "L2GND")
		(6 "In2.Cu" signal "L3")
		(8 "In3.Cu" signal "L4GND")
		(10 "In4.Cu" signal "L5")
		(12 "In5.Cu" signal "L6GND")
		(14 "In6.Cu" signal "L7VCC")
		(16 "In7.Cu" signal "L8VCC")
		(18 "In8.Cu" signal "L9GND")
		(20 "In9.Cu" signal "L10")
		(22 "In10.Cu" signal "L11GND")
		(24 "In11.Cu" signal "L12")
		(26 "In12.Cu" signal "L13GND")
		(2 "B.Cu" signal "BOTTOM")
		(9 "F.Adhes" user "F.Adhesive")
		(11 "B.Adhes" user "B.Adhesive")
		(13 "F.Paste" user "Package Geometry/Pastemask Top")
		(15 "B.Paste" user "Package Geometry/Pastemask Bottom")
		(5 "F.SilkS" user "Ref Des/Silkscreen Top")
		(7 "B.SilkS" user "Ref Des/Silkscreen Bottom")
		(1 "F.Mask" user "Board Geometry/Soldermask Top")
		(3 "B.Mask" user "Board Geometry/Soldermask Bottom")
		(17 "Dwgs.User" user "User.Drawings")
		(19 "Cmts.User" user "User.Comments")
		(21 "Eco1.User" user "User.Eco1")
		(23 "Eco2.User" user "User.Eco2")
		(25 "Edge.Cuts" user "Board Geometry/Outline")
		(27 "Margin" user)
		(31 "F.CrtYd" user "Package Geometry/Place Bound Top")
		(29 "B.CrtYd" user "Package Geometry/Place Bound Bottom")
		(35 "F.Fab" user "Ref Des/Assembly Top")
		(33 "B.Fab" user "Ref Des/Assembly Bottom")
	)
	(footprint ""
		(layer "B.Cu")
		(at 412.75 -46.052232)
		(property "Reference" "R25W74"
			(at 0.8382 -0.67818 0)
			(unlocked yes)
			(layer "B.SilkS")
			(effects
				(font
					(size 0.4064 0.254)
					(thickness 0.1524)
				)
				(justify left mirror)
			)
		)
		(property "Value" ""
			(at 0 0 0)
			(layer "B.Fab")
			(effects
				(font
					(size 1.27 1.27)
				)
				(justify mirror)
			)
		)
		(duplicate_pad_numbers_are_jumpers no)
		(fp_poly
			(pts
				(xy 0.2794 -0.1016) (xy -0.2794 -0.1016) (xy -0.2794 0.9906) (xy 0.2794 0.9906)
			)
			(stroke
				(width 0)
				(type default)
			)
			(fill no)
			(layer "B.CrtYd")
		)
		(fp_line
			(start -0.2794 -0.1016)
			(end 0.2794 -0.1016)
			(stroke
				(width 0.1)
				(type default)
			)
			(layer "B.Fab")
		)
		(fp_line
			(start -0.2794 0.9906)
			(end -0.2794 -0.1016)
			(stroke
				(width 0.1)
				(type default)
			)
			(layer "B.Fab")
		)
		(fp_line
			(start 0.2794 -0.1016)
			(end 0.2794 0.9906)
			(stroke
				(width 0.1)
				(type default)
			)
			(layer "B.Fab")
		)
		(fp_line
			(start 0.2794 0.9906)
			(end -0.2794 0.9906)
			(stroke
				(width 0.1)
				(type default)
			)
			(layer "B.Fab")
		)
		(pad "1" smd rect
			(at 0 0 180)
			(size 0.508 0.508)
			(layers "B.Cu" "B.Mask" "B.Paste")
			(net "RST_PLTRST_BUF_N")
		)
		(pad "2" smd rect
			(at 0 0.889 180)
			(size 0.508 0.508)
			(layers "B.Cu" "B.Mask" "B.Paste")
			(net "RST_BMC_LVC3_N")
		)
		(zone
			(layer "B.Cu")
			(hatch none 0.5)
			(connect_pads
				(clearance 0)
			)
			(min_thickness 0.25)
			(keepout
				(tracks allowed)
				(vias not_allowed)
				(pads allowed)
				(copperpour not_allowed)
				(footprints allowed)
			)
			(placement
				(enabled no)
				(sheetname "")
			)
			(fill
				(thermal_gap 0.5)
				(thermal_bridge_width 0.5)
				(island_removal_mode 0)
			)
			(polygon
				(pts
					(xy 413.004 -45.798232) (xy 412.496 -45.798232) (xy 412.496 -45.417232) (xy 413.004 -45.417232)
				)
			)
		)
		(zone
			(layer "B.Cu")
			(hatch none 0.5)
			(connect_pads
				(clearance 0)
			)
			(min_thickness 0.25)
			(keepout
				(tracks not_allowed)
				(vias allowed)
				(pads allowed)
				(copperpour not_allowed)
				(footprints allowed)
			)
			(placement
				(enabled no)
				(sheetname "")
			)
			(fill
				(thermal_gap 0.5)
				(thermal_bridge_width 0.5)
				(island_removal_mode 0)
			)
			(polygon
				(pts
					(xy 413.004 -45.417232) (xy 412.496 -45.417232) (xy 412.496 -45.798232) (xy 413.004 -45.798232)
				)
			)
		)
	)
	(footprint ""
		(layer "B.Cu")
		(at 20.447 -69.85 180)
		(property "Reference" "R9P29"
			(at 0 0 0)
			(layer "B.SilkS")
			(hide yes)
			(effects
				(font
					(size 1.27 1.27)
				)
				(justify mirror)
			)
		)
		(property "Value" ""
			(at 0 0 0)
			(layer "B.Fab")
			(effects
				(font
					(size 1.27 1.27)
				)
				(justify mirror)
			)
		)
		(duplicate_pad_numbers_are_jumpers no)
		(fp_poly
			(pts
				(xy 0.2794 -0.1016) (xy -0.2794 -0.1016) (xy -0.2794 0.9906) (xy 0.2794 0.9906)
			)
			(stroke
				(width 0)
				(type default)
			)
			(fill no)
			(layer "B.CrtYd")
		)
		(fp_line
			(start 0.2794 0.9906)
			(end -0.2794 0.9906)
			(stroke
				(width 0.1)
				(type default)
			)
			(layer "B.Fab")
		)
		(fp_line
			(start 0.2794 -0.1016)
			(end 0.2794 0.9906)
			(stroke
				(width 0.1)
				(type default)
			)
			(layer "B.Fab")
		)
		(fp_line
			(start -0.2794 0.9906)
			(end -0.2794 -0.1016)
			(stroke
				(width 0.1)
				(type default)
			)
			(layer "B.Fab")
		)
		(fp_line
			(start -0.2794 -0.1016)
			(end 0.2794 -0.1016)
			(stroke
				(width 0.1)
				(type default)
			)
			(layer "B.Fab")
		)
		(pad "1" smd rect
			(at 0 0)
			(size 0.508 0.508)
			(layers "B.Cu" "B.Mask" "B.Paste")
			(net "P12V_PSU")
		)
		(pad "2" smd rect
			(at 0 0.889)
			(size 0.508 0.508)
			(layers "B.Cu" "B.Mask" "B.Paste")
			(net "A_HSC_UV")
		)
		(zone
			(layer "B.Cu")
			(hatch none 0.5)
			(connect_pads
				(clearance 0)
			)
			(min_thickness 0.25)
			(keepout
				(tracks not_allowed)
				(vias allowed)
				(pads allowed)
				(copperpour not_allowed)
				(footprints allowed)
			)
			(placement
				(enabled no)
				(sheetname "")
			)
			(fill
				(thermal_gap 0.5)
				(thermal_bridge_width 0.5)
				(island_removal_mode 0)
			)
			(polygon
				(pts
					(xy 20.193 -70.485) (xy 20.701 -70.485) (xy 20.701 -70.104) (xy 20.193 -70.104)
				)
			)
		)
		(zone
			(layer "B.Cu")
			(hatch none 0.5)
			(connect_pads
				(clearance 0)
			)
			(min_thickness 0.25)
			(keepout
				(tracks allowed)
				(vias not_allowed)
				(pads allowed)
				(copperpour not_allowed)
				(footprints allowed)
			)
			(placement
				(enabled no)
				(sheetname "")
			)
			(fill
				(thermal_gap 0.5)
				(thermal_bridge_width 0.5)
				(island_removal_mode 0)
			)
			(polygon
				(pts
					(xy 20.193 -70.104) (xy 20.701 -70.104) (xy 20.701 -70.485) (xy 20.193 -70.485)
				)
			)
		)
	)
	(footprint ""
		(layer "B.Cu")
		(at 385.217924 -24.885904 90)
		(property "Reference" "C2T20"
			(at 0 0 90)
			(layer "B.SilkS")
			(hide yes)
			(effects
				(font
					(size 1.27 1.27)
				)
				(justify mirror)
			)
		)
		(property "Value" ""
			(at 0 0 90)
			(layer "B.Fab")
			(effects
				(font
					(size 1.27 1.27)
				)
				(justify mirror)
			)
		)
		(duplicate_pad_numbers_are_jumpers no)
		(fp_poly
			(pts
				(xy -0.3048 -0.1016) (xy -0.3048 0.9906) (xy 0.3048 0.9906) (xy 0.3048 -0.1016)
			)
			(stroke
				(width 0)
				(type default)
			)
			(fill no)
			(layer "B.CrtYd")
		)
		(fp_line
			(start 0.3048 -0.1016)
			(end 0.3048 0.9906)
			(stroke
				(width 0.1)
				(type default)
			)
			(layer "B.Fab")
		)
		(fp_line
			(start -0.3048 -0.1016)
			(end 0.3048 -0.1016)
			(stroke
				(width 0.1)
				(type default)
			)
			(layer "B.Fab")
		)
		(fp_line
			(start 0.3048 0.9906)
			(end -0.3048 0.9906)
			(stroke
				(width 0.1)
				(type default)
			)
			(layer "B.Fab")
		)
		(fp_line
			(start -0.3048 0.9906)
			(end -0.3048 -0.1016)
			(stroke
				(width 0.1)
				(type default)
			)
			(layer "B.Fab")
		)
		(pad "1" smd rect
			(at 0 0 270)
			(size 0.508 0.508)
			(layers "B.Cu" "B.Mask" "B.Paste")
			(net "P3E_PCH_M2_TX_C_DP<3>")
		)
		(pad "2" smd rect
			(at 0 0.889 270)
			(size 0.508 0.508)
			(layers "B.Cu" "B.Mask" "B.Paste")
			(net "P3E_PCH_M2_TX_DP<3>")
		)
		(zone
			(layer "B.Cu")
			(hatch none 0.5)
			(connect_pads
				(clearance 0)
			)
			(min_thickness 0.25)
			(keepout
				(tracks allowed)
				(vias not_allowed)
				(pads allowed)
				(copperpour not_allowed)
				(footprints allowed)
			)
			(placement
				(enabled no)
				(sheetname "")
			)
			(fill
				(thermal_gap 0.5)
				(thermal_bridge_width 0.5)
				(island_removal_mode 0)
			)
			(polygon
				(pts
					(xy 385.471924 -25.139904) (xy 385.471924 -24.631904) (xy 385.852924 -24.631904) (xy 385.852924 -25.139904)
				)
			)
		)
		(zone
			(layer "B.Cu")
			(hatch none 0.5)
			(connect_pads
				(clearance 0)
			)
			(min_thickness 0.25)
			(keepout
				(tracks not_allowed)
				(vias allowed)
				(pads allowed)
				(copperpour not_allowed)
				(footprints allowed)
			)
			(placement
				(enabled no)
				(sheetname "")
			)
			(fill
				(thermal_gap 0.5)
				(thermal_bridge_width 0.5)
				(island_removal_mode 0)
			)
			(polygon
				(pts
					(xy 385.852924 -25.139904) (xy 385.852924 -24.631904) (xy 385.471924 -24.631904) (xy 385.471924 -25.139904)
				)
			)
		)
	)
)
